(kicad_pcb
	(version 20260206)
	(generator "pcbnew")
	(generator_version "10.0")
	(general
		(thickness 1.6)
		(legacy_teardrops no)
	)
	(paper "A4")
	(title_block
		(title "Bryce Canyon_IOM_M2_16342-2_OCP.brd")
		(comment 1 "Bryce Canyon / footprints 1035-1042 of 1146")
	)
	(layers
		(0 "F.Cu" signal "TOP")
		(4 "In1.Cu" signal "L2GND")
		(6 "In2.Cu" signal "L3")
		(8 "In3.Cu" signal "L4VCC")
		(10 "In4.Cu" signal "L5VCC")
		(12 "In5.Cu" signal "L6")
		(14 "In6.Cu" signal "L7GND")
		(2 "B.Cu" signal "BOTTOM")
		(9 "F.Adhes" user "F.Adhesive")
		(11 "B.Adhes" user "B.Adhesive")
		(13 "F.Paste" user "Package Geometry/Pastemask Top")
		(15 "B.Paste" user "Package Geometry/Pastemask Bottom")
		(5 "F.SilkS" user "Ref Des/Silkscreen Top")
		(7 "B.SilkS" user "Ref Des/Silkscreen Bottom")
		(1 "F.Mask" user "Board Geometry/Soldermask Top")
		(3 "B.Mask" user "Board Geometry/Soldermask Bottom")
		(17 "Dwgs.User" user "User.Drawings")
		(19 "Cmts.User" user "User.Comments")
		(21 "Eco1.User" user "User.Eco1")
		(23 "Eco2.User" user "User.Eco2")
		(25 "Edge.Cuts" user "Board Geometry/Outline")
		(27 "Margin" user)
		(31 "F.CrtYd" user "Package Geometry/Place Bound Top")
		(29 "B.CrtYd" user "Package Geometry/Place Bound Bottom")
		(35 "F.Fab" user "Ref Des/Assembly Top")
		(33 "B.Fab" user "Ref Des/Assembly Bottom")
	)
	(footprint ""
		(layer "B.Cu")
		(at 50.09642 -145.96618)
		(property "Reference" "C98"
			(at 0 0 0)
			(layer "B.SilkS")
			(hide yes)
			(effects
				(font
					(size 1.27 1.27)
				)
				(justify mirror)
			)
		)
		(property "Value" "SC1U16V3KX-5GP"
			(at 0 -2.8194 0)
			(unlocked yes)
			(layer "B.Fab")
			(hide yes)
			(effects
				(font
					(size 1.016 1.016)
					(thickness 0.1524)
				)
				(justify mirror)
			)
		)
		(property "Device Type" "C603H36"
			(at 0 -4.3434 0)
			(unlocked yes)
			(layer "B.Fab")
			(hide yes)
			(effects
				(font
					(size 1.016 1.016)
					(thickness 0.1524)
				)
				(justify mirror)
			)
		)
		(duplicate_pad_numbers_are_jumpers no)
		(fp_line
			(start -0.508 0)
			(end 0.508 0)
			(stroke
				(width 0.2032)
				(type default)
			)
			(layer "B.SilkS")
		)
		(fp_rect
			(start 0.5842 1.3335)
			(end -0.5842 -1.3335)
			(stroke
				(width 0)
				(type default)
			)
			(fill no)
			(layer "B.CrtYd")
		)
		(fp_rect
			(start 0.5842 1.3335)
			(end -0.5842 -1.3335)
			(stroke
				(width 0)
				(type default)
			)
			(fill no)
			(layer "B.Fab")
		)
		(pad "1" smd custom
			(at 0 -0.762 180)
			(size 0.2159 0.2159)
			(layers "B.Cu" "B.Mask" "B.Paste")
			(net "P3V3_STBY")
			(options
				(clearance outline)
				(anchor circle)
			)
			(primitives
				(gr_poly
					(pts
						(arc
							(start -0.3302 0.4318)
							(mid -0.402042 0.402042)
							(end -0.4318 0.3302)
						)
						(arc
							(start -0.4318 -0.3302)
							(mid -0.402042 -0.402042)
							(end -0.3302 -0.4318)
						)
						(arc
							(start 0.3302 -0.4318)
							(mid 0.402042 -0.402042)
							(end 0.4318 -0.3302)
						)
						(arc
							(start 0.4318 0.3302)
							(mid 0.402042 0.402042)
							(end 0.3302 0.4318)
						)
					)
					(width 0)
					(fill yes)
				)
			)
		)
		(pad "2" smd custom
			(at 0 0.762 180)
			(size 0.2159 0.2159)
			(layers "B.Cu" "B.Mask" "B.Paste")
			(net "GND")
			(options
				(clearance outline)
				(anchor circle)
			)
			(primitives
				(gr_poly
					(pts
						(arc
							(start -0.3302 0.4318)
							(mid -0.402042 0.402042)
							(end -0.4318 0.3302)
						)
						(arc
							(start -0.4318 -0.3302)
							(mid -0.402042 -0.402042)
							(end -0.3302 -0.4318)
						)
						(arc
							(start 0.3302 -0.4318)
							(mid 0.402042 -0.402042)
							(end 0.4318 -0.3302)
						)
						(arc
							(start 0.4318 0.3302)
							(mid 0.402042 0.402042)
							(end 0.3302 0.4318)
						)
					)
					(width 0)
					(fill yes)
				)
			)
		)
	)
	(footprint ""
		(layer "B.Cu")
		(at 55.372 -118.6942 90)
		(property "Reference" "C506"
			(at 0 0 90)
			(layer "B.SilkS")
			(hide yes)
			(effects
				(font
					(size 1.27 1.27)
				)
				(justify mirror)
			)
		)
		(property "Value" "SCD1U16V2KX-3GP"
			(at -1.1811 -2.7051 90)
			(unlocked yes)
			(layer "B.Fab")
			(hide yes)
			(effects
				(font
					(size 1.016 1.016)
					(thickness 0.1524)
				)
				(justify mirror)
			)
		)
		(property "Device Type" "C402H22"
			(at -1.1811 -4.2291 90)
			(unlocked yes)
			(layer "B.Fab")
			(hide yes)
			(effects
				(font
					(size 1.016 1.016)
					(thickness 0.1524)
				)
				(justify mirror)
			)
		)
		(duplicate_pad_numbers_are_jumpers no)
		(fp_rect
			(start 0.4318 0.9525)
			(end -0.4318 -0.9525)
			(stroke
				(width 0)
				(type default)
			)
			(fill no)
			(layer "B.CrtYd")
		)
		(fp_rect
			(start 0.4318 0.9525)
			(end -0.4318 -0.9525)
			(stroke
				(width 0)
				(type default)
			)
			(fill no)
			(layer "B.Fab")
		)
		(pad "1" smd custom
			(at 0 -0.4445 270)
			(size 0.1524 0.1524)
			(layers "B.Cu" "B.Mask" "B.Paste")
			(net "P3V3_STBY")
			(options
				(clearance outline)
				(anchor circle)
			)
			(primitives
				(gr_poly
					(pts
						(arc
							(start 0.3048 0.2032)
							(mid 0.275042 0.275042)
							(end 0.2032 0.3048)
						)
						(arc
							(start -0.2032 0.3048)
							(mid -0.275042 0.275042)
							(end -0.3048 0.2032)
						)
						(arc
							(start -0.3048 -0.2032)
							(mid -0.275042 -0.275042)
							(end -0.2032 -0.3048)
						)
						(arc
							(start 0.2032 -0.3048)
							(mid 0.275042 -0.275042)
							(end 0.3048 -0.2032)
						)
					)
					(width 0)
					(fill yes)
				)
			)
		)
		(pad "2" smd custom
			(at 0 0.4445 270)
			(size 0.1524 0.1524)
			(layers "B.Cu" "B.Mask" "B.Paste")
			(net "GND")
			(options
				(clearance outline)
				(anchor circle)
			)
			(primitives
				(gr_poly
					(pts
						(arc
							(start 0.3048 0.2032)
							(mid 0.275042 0.275042)
							(end 0.2032 0.3048)
						)
						(arc
							(start -0.2032 0.3048)
							(mid -0.275042 0.275042)
							(end -0.3048 0.2032)
						)
						(arc
							(start -0.3048 -0.2032)
							(mid -0.275042 -0.275042)
							(end -0.2032 -0.3048)
						)
						(arc
							(start 0.2032 -0.3048)
							(mid 0.275042 -0.275042)
							(end 0.3048 -0.2032)
						)
					)
					(width 0)
					(fill yes)
				)
			)
		)
	)
	(footprint ""
		(layer "B.Cu")
		(at 46.8376 -154.8384 180)
		(property "Reference" "R311"
			(at 0 0 0)
			(layer "B.SilkS")
			(hide yes)
			(effects
				(font
					(size 1.27 1.27)
				)
				(justify mirror)
			)
		)
		(property "Value" "4K7R2F-GP"
			(at -0.064008 -3.993896 180)
			(unlocked yes)
			(layer "B.Fab")
			(hide yes)
			(effects
				(font
					(size 1.016 1.016)
					(thickness 0.1524)
				)
				(justify mirror)
			)
		)
		(property "Device Type" "R402H16"
			(at -0.064008 -5.517896 180)
			(unlocked yes)
			(layer "B.Fab")
			(hide yes)
			(effects
				(font
					(size 1.016 1.016)
					(thickness 0.1524)
				)
				(justify mirror)
			)
		)
		(duplicate_pad_numbers_are_jumpers no)
		(fp_line
			(start 0.508 -0.9398)
			(end 0.508 0.9398)
			(stroke
				(width 0.1524)
				(type default)
			)
			(layer "B.SilkS")
		)
		(fp_line
			(start -0.508 -0.9398)
			(end 0.508 -0.9398)
			(stroke
				(width 0.1524)
				(type default)
			)
			(layer "B.SilkS")
		)
		(fp_rect
			(start 0.508 0.9398)
			(end -0.508 -0.9398)
			(stroke
				(width 0)
				(type default)
			)
			(fill no)
			(layer "B.CrtYd")
		)
		(fp_rect
			(start 0.508 0.9398)
			(end -0.508 -0.9398)
			(stroke
				(width 0)
				(type default)
			)
			(fill no)
			(layer "B.Fab")
		)
		(pad "1" smd custom
			(at 0 -0.4445)
			(size 0.1397 0.1397)
			(layers "B.Cu" "B.Mask" "B.Paste")
			(net "BOARD_REV_2")
			(options
				(clearance outline)
				(anchor circle)
			)
			(primitives
				(gr_poly
					(pts
						(arc
							(start -0.1778 0.2794)
							(mid -0.249642 0.249642)
							(end -0.2794 0.1778)
						)
						(arc
							(start -0.2794 -0.1778)
							(mid -0.249642 -0.249642)
							(end -0.1778 -0.2794)
						)
						(arc
							(start 0.1778 -0.2794)
							(mid 0.249642 -0.249642)
							(end 0.2794 -0.1778)
						)
						(arc
							(start 0.2794 0.1778)
							(mid 0.249642 0.249642)
							(end 0.1778 0.2794)
						)
					)
					(width 0)
					(fill yes)
				)
			)
		)
		(pad "2" smd custom
			(at 0 0.4445)
			(size 0.1397 0.1397)
			(layers "B.Cu" "B.Mask" "B.Paste")
			(net "P3V3_STBY")
			(options
				(clearance outline)
				(anchor circle)
			)
			(primitives
				(gr_poly
					(pts
						(arc
							(start -0.1778 0.2794)
							(mid -0.249642 0.249642)
							(end -0.2794 0.1778)
						)
						(arc
							(start -0.2794 -0.1778)
							(mid -0.249642 -0.249642)
							(end -0.1778 -0.2794)
						)
						(arc
							(start 0.1778 -0.2794)
							(mid 0.249642 -0.249642)
							(end 0.2794 -0.1778)
						)
						(arc
							(start 0.2794 0.1778)
							(mid 0.249642 0.249642)
							(end 0.1778 0.2794)
						)
					)
					(width 0)
					(fill yes)
				)
			)
		)
	)
	(footprint ""
		(layer "B.Cu")
		(at 63.8048 -144.0434 90)
		(property "Reference" "R196"
			(at 0 0 90)
			(layer "B.SilkS")
			(hide yes)
			(effects
				(font
					(size 1.27 1.27)
				)
				(justify mirror)
			)
		)
		(property "Value" "2K2R2F-GP"
			(at -0.064008 -3.993896 90)
			(unlocked yes)
			(layer "B.Fab")
			(hide yes)
			(effects
				(font
					(size 1.016 1.016)
					(thickness 0.1524)
				)
				(justify mirror)
			)
		)
		(property "Device Type" "R402H16"
			(at -0.064008 -5.517896 90)
			(unlocked yes)
			(layer "B.Fab")
			(hide yes)
			(effects
				(font
					(size 1.016 1.016)
					(thickness 0.1524)
				)
				(justify mirror)
			)
		)
		(duplicate_pad_numbers_are_jumpers no)
		(fp_line
			(start 0.508 -0.9398)
			(end 0.508 0.9398)
			(stroke
				(width 0.1524)
				(type default)
			)
			(layer "B.SilkS")
		)
		(fp_line
			(start -0.508 -0.9398)
			(end 0.508 -0.9398)
			(stroke
				(width 0.1524)
				(type default)
			)
			(layer "B.SilkS")
		)
		(fp_rect
			(start 0.508 0.9398)
			(end -0.508 -0.9398)
			(stroke
				(width 0)
				(type default)
			)
			(fill no)
			(layer "B.CrtYd")
		)
		(fp_rect
			(start 0.508 0.9398)
			(end -0.508 -0.9398)
			(stroke
				(width 0)
				(type default)
			)
			(fill no)
			(layer "B.Fab")
		)
		(pad "1" smd custom
			(at 0 -0.4445 270)
			(size 0.1397 0.1397)
			(layers "B.Cu" "B.Mask" "B.Paste")
			(net "I2C_EXP_LOC_SDA_OUT")
			(options
				(clearance outline)
				(anchor circle)
			)
			(primitives
				(gr_poly
					(pts
						(arc
							(start -0.1778 0.2794)
							(mid -0.249642 0.249642)
							(end -0.2794 0.1778)
						)
						(arc
							(start -0.2794 -0.1778)
							(mid -0.249642 -0.249642)
							(end -0.1778 -0.2794)
						)
						(arc
							(start 0.1778 -0.2794)
							(mid 0.249642 -0.249642)
							(end 0.2794 -0.1778)
						)
						(arc
							(start 0.2794 0.1778)
							(mid 0.249642 0.249642)
							(end 0.1778 0.2794)
						)
					)
					(width 0)
					(fill yes)
				)
			)
		)
		(pad "2" smd custom
			(at 0 0.4445 270)
			(size 0.1397 0.1397)
			(layers "B.Cu" "B.Mask" "B.Paste")
			(net "P3V3_STBY")
			(options
				(clearance outline)
				(anchor circle)
			)
			(primitives
				(gr_poly
					(pts
						(arc
							(start -0.1778 0.2794)
							(mid -0.249642 0.249642)
							(end -0.2794 0.1778)
						)
						(arc
							(start -0.2794 -0.1778)
							(mid -0.249642 -0.249642)
							(end -0.1778 -0.2794)
						)
						(arc
							(start 0.1778 -0.2794)
							(mid 0.249642 -0.249642)
							(end 0.2794 -0.1778)
						)
						(arc
							(start 0.2794 0.1778)
							(mid 0.249642 0.249642)
							(end 0.1778 0.2794)
						)
					)
					(width 0)
					(fill yes)
				)
			)
		)
	)
	(footprint ""
		(layer "B.Cu")
		(at 46.9138 -140.208)
		(property "Reference" "TP27"
			(at 0 0 0)
			(layer "B.SilkS")
			(hide yes)
			(effects
				(font
					(size 1.27 1.27)
				)
				(justify mirror)
			)
		)
		(property "Value" "TPAD28-2-GP"
			(at 0.0127 -1.6637 0)
			(unlocked yes)
			(layer "B.Fab")
			(hide yes)
			(effects
				(font
					(size 1.016 1.016)
					(thickness 0.1524)
				)
				(justify mirror)
			)
		)
		(property "Device Type" "TPAD28"
			(at 0.0127 -3.1877 0)
			(unlocked yes)
			(layer "B.Fab")
			(hide yes)
			(effects
				(font
					(size 1.016 1.016)
					(thickness 0.1524)
				)
				(justify mirror)
			)
		)
		(duplicate_pad_numbers_are_jumpers no)
		(fp_poly
			(pts
				(arc
					(start 0.3556 0)
					(mid -0.3556 0)
					(end 0.3556 0)
				)
			)
			(stroke
				(width 0)
				(type default)
			)
			(fill no)
			(layer "B.CrtYd")
		)
		(fp_poly
			(pts
				(arc
					(start 0.6096 0)
					(mid -0.6096 0)
					(end 0.6096 0)
				)
			)
			(stroke
				(width 0)
				(type default)
			)
			(fill no)
			(layer "B.Fab")
		)
		(pad "1" smd circle
			(at 0 0 180)
			(size 0.7112 0.7112)
			(layers "B.Cu" "B.Mask" "B.Paste")
			(net "TP_BMC_GPIOR1")
		)
	)
	(footprint ""
		(layer "B.Cu")
		(at 125.349 -14.351)
		(property "Reference" "C144"
			(at 0 0 0)
			(layer "B.SilkS")
			(hide yes)
			(effects
				(font
					(size 1.27 1.27)
				)
				(justify mirror)
			)
		)
		(property "Value" "SC1U16V3KX-5GP"
			(at 0 -2.8194 0)
			(unlocked yes)
			(layer "B.Fab")
			(hide yes)
			(effects
				(font
					(size 1.016 1.016)
					(thickness 0.1524)
				)
				(justify mirror)
			)
		)
		(property "Device Type" "C603H36"
			(at 0 -4.3434 0)
			(unlocked yes)
			(layer "B.Fab")
			(hide yes)
			(effects
				(font
					(size 1.016 1.016)
					(thickness 0.1524)
				)
				(justify mirror)
			)
		)
		(duplicate_pad_numbers_are_jumpers no)
		(fp_line
			(start -0.508 0)
			(end 0.508 0)
			(stroke
				(width 0.2032)
				(type default)
			)
			(layer "B.SilkS")
		)
		(fp_rect
			(start 0.5842 1.3335)
			(end -0.5842 -1.3335)
			(stroke
				(width 0)
				(type default)
			)
			(fill no)
			(layer "B.CrtYd")
		)
		(fp_rect
			(start 0.5842 1.3335)
			(end -0.5842 -1.3335)
			(stroke
				(width 0)
				(type default)
			)
			(fill no)
			(layer "B.Fab")
		)
		(pad "1" smd custom
			(at 0 -0.762 180)
			(size 0.2159 0.2159)
			(layers "B.Cu" "B.Mask" "B.Paste")
			(net "MB0_CM_OV_R")
			(options
				(clearance outline)
				(anchor circle)
			)
			(primitives
				(gr_poly
					(pts
						(arc
							(start -0.3302 0.4318)
							(mid -0.402042 0.402042)
							(end -0.4318 0.3302)
						)
						(arc
							(start -0.4318 -0.3302)
							(mid -0.402042 -0.402042)
							(end -0.3302 -0.4318)
						)
						(arc
							(start 0.3302 -0.4318)
							(mid 0.402042 -0.402042)
							(end 0.4318 -0.3302)
						)
						(arc
							(start 0.4318 0.3302)
							(mid 0.402042 0.402042)
							(end 0.3302 0.4318)
						)
					)
					(width 0)
					(fill yes)
				)
			)
		)
		(pad "2" smd custom
			(at 0 0.762 180)
			(size 0.2159 0.2159)
			(layers "B.Cu" "B.Mask" "B.Paste")
			(net "AGND_CURRENT_MON")
			(options
				(clearance outline)
				(anchor circle)
			)
			(primitives
				(gr_poly
					(pts
						(arc
							(start -0.3302 0.4318)
							(mid -0.402042 0.402042)
							(end -0.4318 0.3302)
						)
						(arc
							(start -0.4318 -0.3302)
							(mid -0.402042 -0.402042)
							(end -0.3302 -0.4318)
						)
						(arc
							(start 0.3302 -0.4318)
							(mid 0.402042 -0.402042)
							(end 0.4318 -0.3302)
						)
						(arc
							(start 0.4318 0.3302)
							(mid 0.402042 0.402042)
							(end 0.3302 0.4318)
						)
					)
					(width 0)
					(fill yes)
				)
			)
		)
	)
	(footprint ""
		(layer "B.Cu")
		(at 170.035728 -124.638308 -90)
		(property "Reference" "C619"
			(at 0 0 90)
			(layer "B.SilkS")
			(hide yes)
			(effects
				(font
					(size 1.27 1.27)
				)
				(justify mirror)
			)
		)
		(property "Value" "SCD1U16V2KX-3GP"
			(at -1.1811 -2.7051 270)
			(unlocked yes)
			(layer "B.Fab")
			(hide yes)
			(effects
				(font
					(size 1.016 1.016)
					(thickness 0.1524)
				)
				(justify mirror)
			)
		)
		(property "Device Type" "C402H22"
			(at -1.1811 -4.2291 270)
			(unlocked yes)
			(layer "B.Fab")
			(hide yes)
			(effects
				(font
					(size 1.016 1.016)
					(thickness 0.1524)
				)
				(justify mirror)
			)
		)
		(duplicate_pad_numbers_are_jumpers no)
		(fp_rect
			(start 0.4318 0.9525)
			(end -0.4318 -0.9525)
			(stroke
				(width 0)
				(type default)
			)
			(fill no)
			(layer "B.CrtYd")
		)
		(fp_rect
			(start 0.4318 0.9525)
			(end -0.4318 -0.9525)
			(stroke
				(width 0)
				(type default)
			)
			(fill no)
			(layer "B.Fab")
		)
		(pad "1" smd custom
			(at 0 -0.4445 90)
			(size 0.1524 0.1524)
			(layers "B.Cu" "B.Mask" "B.Paste")
			(net "P3V3_M2")
			(options
				(clearance outline)
				(anchor circle)
			)
			(primitives
				(gr_poly
					(pts
						(arc
							(start 0.3048 0.2032)
							(mid 0.275042 0.275042)
							(end 0.2032 0.3048)
						)
						(arc
							(start -0.2032 0.3048)
							(mid -0.275042 0.275042)
							(end -0.3048 0.2032)
						)
						(arc
							(start -0.3048 -0.2032)
							(mid -0.275042 -0.275042)
							(end -0.2032 -0.3048)
						)
						(arc
							(start 0.2032 -0.3048)
							(mid 0.275042 -0.275042)
							(end 0.3048 -0.2032)
						)
					)
					(width 0)
					(fill yes)
				)
			)
		)
		(pad "2" smd custom
			(at 0 0.4445 90)
			(size 0.1524 0.1524)
			(layers "B.Cu" "B.Mask" "B.Paste")
			(net "GND")
			(options
				(clearance outline)
				(anchor circle)
			)
			(primitives
				(gr_poly
					(pts
						(arc
							(start 0.3048 0.2032)
							(mid 0.275042 0.275042)
							(end 0.2032 0.3048)
						)
						(arc
							(start -0.2032 0.3048)
							(mid -0.275042 0.275042)
							(end -0.3048 0.2032)
						)
						(arc
							(start -0.3048 -0.2032)
							(mid -0.275042 -0.275042)
							(end -0.2032 -0.3048)
						)
						(arc
							(start 0.2032 -0.3048)
							(mid 0.275042 -0.275042)
							(end 0.3048 -0.2032)
						)
					)
					(width 0)
					(fill yes)
				)
			)
		)
	)
	(footprint ""
		(layer "B.Cu")
		(at 48.079406 -147.98675 90)
		(property "Reference" "C107"
			(at 0 0 90)
			(layer "B.SilkS")
			(hide yes)
			(effects
				(font
					(size 1.27 1.27)
				)
				(justify mirror)
			)
		)
		(property "Value" "SC1U16V3KX-5GP"
			(at 0 -2.8194 90)
			(unlocked yes)
			(layer "B.Fab")
			(hide yes)
			(effects
				(font
					(size 1.016 1.016)
					(thickness 0.1524)
				)
				(justify mirror)
			)
		)
		(property "Device Type" "C603H36"
			(at 0 -4.3434 90)
			(unlocked yes)
			(layer "B.Fab")
			(hide yes)
			(effects
				(font
					(size 1.016 1.016)
					(thickness 0.1524)
				)
				(justify mirror)
			)
		)
		(duplicate_pad_numbers_are_jumpers no)
		(fp_line
			(start -0.508 0)
			(end 0.508 0)
			(stroke
				(width 0.2032)
				(type default)
			)
			(layer "B.SilkS")
		)
		(fp_rect
			(start 0.5842 1.3335)
			(end -0.5842 -1.3335)
			(stroke
				(width 0)
				(type default)
			)
			(fill no)
			(layer "B.CrtYd")
		)
		(fp_rect
			(start 0.5842 1.3335)
			(end -0.5842 -1.3335)
			(stroke
				(width 0)
				(type default)
			)
			(fill no)
			(layer "B.Fab")
		)
		(pad "1" smd custom
			(at 0 -0.762 270)
			(size 0.2159 0.2159)
			(layers "B.Cu" "B.Mask" "B.Paste")
			(net "P1V15_STBY")
			(options
				(clearance outline)
				(anchor circle)
			)
			(primitives
				(gr_poly
					(pts
						(arc
							(start -0.3302 0.4318)
							(mid -0.402042 0.402042)
							(end -0.4318 0.3302)
						)
						(arc
							(start -0.4318 -0.3302)
							(mid -0.402042 -0.402042)
							(end -0.3302 -0.4318)
						)
						(arc
							(start 0.3302 -0.4318)
							(mid 0.402042 -0.402042)
							(end 0.4318 -0.3302)
						)
						(arc
							(start 0.4318 0.3302)
							(mid 0.402042 0.402042)
							(end 0.3302 0.4318)
						)
					)
					(width 0)
					(fill yes)
				)
			)
		)
		(pad "2" smd custom
			(at 0 0.762 270)
			(size 0.2159 0.2159)
			(layers "B.Cu" "B.Mask" "B.Paste")
			(net "GND")
			(options
				(clearance outline)
				(anchor circle)
			)
			(primitives
				(gr_poly
					(pts
						(arc
							(start -0.3302 0.4318)
							(mid -0.402042 0.402042)
							(end -0.4318 0.3302)
						)
						(arc
							(start -0.4318 -0.3302)
							(mid -0.402042 -0.402042)
							(end -0.3302 -0.4318)
						)
						(arc
							(start 0.3302 -0.4318)
							(mid 0.402042 -0.402042)
							(end 0.4318 -0.3302)
						)
						(arc
							(start 0.4318 0.3302)
							(mid 0.402042 0.402042)
							(end 0.3302 0.4318)
						)
					)
					(width 0)
					(fill yes)
				)
			)
		)
	)
)
